# S9S_MB_2U (Grand Teton) — schematic netlist excerpt (pin names and nets, part order shuffled) for the footprints in the layout excerpt that follows; sources: Cadence DE-HDL packaged netlist, KiCad conversion of 03242023_DA0F0TMBIJ0_F0T_Motherboard_J_brd_V01_OCP.brd

PC589  Q_CAPP  560UF 2.5V 20% OSCON  pkg THLF  page 285 : A = PVCCIN_CPU1 ; B = GND
PC1234  Q_CAP  100NF 50V 10% X7R  pkg C0402  page 263 : A = SW_P1V8_PCH_AUX_FLT ; B = GND
PC2198  Q_CAP  1UF 25V 10% X6S  pkg C0402  page 193 : A = P12V_AUX ; B = GND

(kicad_pcb
	(version 20260206)
	(generator "pcbnew")
	(generator_version "10.0")
	(general
		(thickness 1.6)
		(legacy_teardrops no)
	)
	(paper "A4")
	(title_block
		(title "03242023_DA0F0TMBIJ0_F0T_Motherboard_J_brd_V01_OCP.brd")
		(comment 1 "Grand Teton / footprints 2270-2272 of 6105")
	)
	(layers
		(0 "F.Cu" signal "TOP")
		(4 "In1.Cu" signal "GND")
		(6 "In2.Cu" signal "IN1")
		(8 "In3.Cu" signal "GND1")
		(10 "In4.Cu" signal "IN2")
		(12 "In5.Cu" signal "GND2")
		(14 "In6.Cu" signal "IN3")
		(16 "In7.Cu" signal "GND3")
		(18 "In8.Cu" signal "VCC")
		(20 "In9.Cu" signal "VCC1")
		(22 "In10.Cu" signal "GND4")
		(24 "In11.Cu" signal "IN4")
		(26 "In12.Cu" signal "GND5")
		(28 "In13.Cu" signal "IN5")
		(30 "In14.Cu" signal "GND6")
		(32 "In15.Cu" signal "IN6")
		(34 "In16.Cu" signal "GND7")
		(2 "B.Cu" signal "BOTTOM")
		(9 "F.Adhes" user "F.Adhesive")
		(11 "B.Adhes" user "B.Adhesive")
		(13 "F.Paste" user "Package Geometry/Pastemask Top")
		(15 "B.Paste" user "Package Geometry/Pastemask Bottom")
		(5 "F.SilkS" user "Ref Des/Silkscreen Top")
		(7 "B.SilkS" user "Ref Des/Silkscreen Bottom")
		(1 "F.Mask" user "Board Geometry/Soldermask Top")
		(3 "B.Mask" user "Board Geometry/Soldermask Bottom")
		(17 "Dwgs.User" user "User.Drawings")
		(19 "Cmts.User" user "User.Comments")
		(21 "Eco1.User" user "User.Eco1")
		(23 "Eco2.User" user "User.Eco2")
		(25 "Edge.Cuts" user "Board Geometry/Outline")
		(27 "Margin" user)
		(31 "F.CrtYd" user "Package Geometry/Place Bound Top")
		(29 "B.CrtYd" user "Package Geometry/Place Bound Bottom")
		(35 "F.Fab" user "Ref Des/Assembly Top")
		(33 "B.Fab" user "Ref Des/Assembly Bottom")
	)
	(footprint ""
		(layer "F.Cu")
		(at 259.89788 -46.634146 90)
		(property "Reference" "PC2198"
			(at 0 0 90)
			(layer "F.SilkS")
			(hide yes)
			(effects
				(font
					(size 1.27 1.27)
				)
			)
		)
		(property "Value" ""
			(at 0 0 90)
			(layer "F.Fab")
			(effects
				(font
					(size 1.27 1.27)
				)
			)
		)
		(duplicate_pad_numbers_are_jumpers no)
		(fp_line
			(start 0.7874 -0.4064)
			(end 0.7874 0.4064)
			(stroke
				(width 0.1524)
				(type default)
			)
			(layer "F.SilkS")
		)
		(fp_line
			(start -0.7874 -0.4064)
			(end 0.7874 -0.4064)
			(stroke
				(width 0.1524)
				(type default)
			)
			(layer "F.SilkS")
		)
		(fp_line
			(start 0.7874 0.4064)
			(end -0.7874 0.4064)
			(stroke
				(width 0.1524)
				(type default)
			)
			(layer "F.SilkS")
		)
		(fp_line
			(start -0.7874 0.4064)
			(end -0.7874 -0.4064)
			(stroke
				(width 0.1524)
				(type default)
			)
			(layer "F.SilkS")
		)
		(fp_line
			(start -0.12065 -0.305054)
			(end -0.12065 -0.2794)
			(stroke
				(width 0.1)
				(type default)
			)
			(layer "F.Fab")
		)
		(fp_line
			(start -0.67945 -0.305054)
			(end -0.12065 -0.305054)
			(stroke
				(width 0.1)
				(type default)
			)
			(layer "F.Fab")
		)
		(fp_line
			(start 0.67945 -0.3048)
			(end 0.67945 0.3048)
			(stroke
				(width 0.1)
				(type default)
			)
			(layer "F.Fab")
		)
		(fp_line
			(start 0.12065 -0.3048)
			(end 0.67945 -0.3048)
			(stroke
				(width 0.1)
				(type default)
			)
			(layer "F.Fab")
		)
		(fp_line
			(start 0.12065 -0.2794)
			(end 0.12065 -0.3048)
			(stroke
				(width 0.1)
				(type default)
			)
			(layer "F.Fab")
		)
		(fp_line
			(start -0.12065 -0.2794)
			(end 0.12065 -0.2794)
			(stroke
				(width 0.1)
				(type default)
			)
			(layer "F.Fab")
		)
		(fp_line
			(start 0.120396 0.2794)
			(end -0.12065 0.2794)
			(stroke
				(width 0.1)
				(type default)
			)
			(layer "F.Fab")
		)
		(fp_line
			(start -0.12065 0.2794)
			(end -0.12065 0.3048)
			(stroke
				(width 0.1)
				(type default)
			)
			(layer "F.Fab")
		)
		(fp_line
			(start 0.67945 0.3048)
			(end 0.120396 0.3048)
			(stroke
				(width 0.1)
				(type default)
			)
			(layer "F.Fab")
		)
		(fp_line
			(start 0.120396 0.3048)
			(end 0.120396 0.2794)
			(stroke
				(width 0.1)
				(type default)
			)
			(layer "F.Fab")
		)
		(fp_line
			(start -0.12065 0.3048)
			(end -0.67945 0.3048)
			(stroke
				(width 0.1)
				(type default)
			)
			(layer "F.Fab")
		)
		(fp_line
			(start -0.67945 0.3048)
			(end -0.67945 -0.305054)
			(stroke
				(width 0.1)
				(type default)
			)
			(layer "F.Fab")
		)
		(pad "1" smd circle
			(at -0.40005 0 90)
			(size 0 0)
			(layers "F.Cu" "F.Mask" "F.Paste")
			(net "P12V_AUX")
		)
		(pad "2" smd circle
			(at 0.40005 0 90)
			(size 0 0)
			(layers "F.Cu" "F.Mask" "F.Paste")
			(net "GND")
		)
	)
	(footprint ""
		(layer "F.Cu")
		(at 104.723438 -315.66739 90)
		(property "Reference" "PC589"
			(at 0 0 90)
			(layer "F.SilkS")
			(hide yes)
			(effects
				(font
					(size 1.27 1.27)
				)
			)
		)
		(property "Value" ""
			(at 0 0 90)
			(layer "F.Fab")
			(effects
				(font
					(size 1.27 1.27)
				)
			)
		)
		(duplicate_pad_numbers_are_jumpers no)
		(fp_line
			(start 2.750058 0.999998)
			(end -2.750058 0.999998)
			(stroke
				(width 0.1524)
				(type default)
			)
			(layer "F.SilkS")
		)
		(fp_circle
			(center 0 0.999998)
			(end 0 3.750056)
			(stroke
				(width 0.1524)
				(type default)
			)
			(fill no)
			(layer "F.SilkS")
		)
		(fp_poly
			(pts
				(arc
					(start 2.750058 0.999998)
					(mid 0 3.750056)
					(end -2.750058 0.999998)
				)
			)
			(stroke
				(width 0)
				(type default)
			)
			(fill yes)
			(layer "F.SilkS")
		)
		(fp_circle
			(center 0 0.999998)
			(end 0 3.750056)
			(stroke
				(width 0.1)
				(type default)
			)
			(fill no)
			(layer "F.Fab")
		)
		(pad "1" thru_hole rect
			(at 0 0 90)
			(size 1.5748 1.5748)
			(drill 1.0668)
			(layers "*.Cu" "*.Mask")
			(remove_unused_layers no)
			(net "PVCCIN_CPU1")
			(clearance 0)
			(padstack
				(mode front_inner_back)
				(layer "Inner"
					(shape circle)
					(size 1.5748 1.5748)
					(clearance 0)
				)
				(layer "B.Cu"
					(shape rect)
					(size 1.5748 1.5748)
					(clearance 0)
				)
			)
		)
		(pad "2" thru_hole circle
			(at 0 1.999996 90)
			(size 1.5748 1.5748)
			(drill 1.0668)
			(layers "*.Cu" "*.Mask")
			(remove_unused_layers no)
			(net "GND")
			(clearance 0)
		)
	)
	(footprint ""
		(layer "F.Cu")
		(at 386.544312 -76.39685 90)
		(property "Reference" "PC1234"
			(at 0 0 90)
			(layer "F.SilkS")
			(hide yes)
			(effects
				(font
					(size 1.27 1.27)
				)
			)
		)
		(property "Value" ""
			(at 0 0 90)
			(layer "F.Fab")
			(effects
				(font
					(size 1.27 1.27)
				)
			)
		)
		(duplicate_pad_numbers_are_jumpers no)
		(fp_line
			(start 0.7874 -0.4064)
			(end 0.7874 0.4064)
			(stroke
				(width 0.1524)
				(type default)
			)
			(layer "F.SilkS")
		)
		(fp_line
			(start -0.7874 -0.4064)
			(end 0.7874 -0.4064)
			(stroke
				(width 0.1524)
				(type default)
			)
			(layer "F.SilkS")
		)
		(fp_line
			(start 0.7874 0.4064)
			(end -0.7874 0.4064)
			(stroke
				(width 0.1524)
				(type default)
			)
			(layer "F.SilkS")
		)
		(fp_line
			(start -0.7874 0.4064)
			(end -0.7874 -0.4064)
			(stroke
				(width 0.1524)
				(type default)
			)
			(layer "F.SilkS")
		)
		(fp_line
			(start -0.12065 -0.305054)
			(end -0.12065 -0.2794)
			(stroke
				(width 0.1)
				(type default)
			)
			(layer "F.Fab")
		)
		(fp_line
			(start -0.67945 -0.305054)
			(end -0.12065 -0.305054)
			(stroke
				(width 0.1)
				(type default)
			)
			(layer "F.Fab")
		)
		(fp_line
			(start 0.67945 -0.3048)
			(end 0.67945 0.3048)
			(stroke
				(width 0.1)
				(type default)
			)
			(layer "F.Fab")
		)
		(fp_line
			(start 0.12065 -0.3048)
			(end 0.67945 -0.3048)
			(stroke
				(width 0.1)
				(type default)
			)
			(layer "F.Fab")
		)
		(fp_line
			(start 0.12065 -0.2794)
			(end 0.12065 -0.3048)
			(stroke
				(width 0.1)
				(type default)
			)
			(layer "F.Fab")
		)
		(fp_line
			(start -0.12065 -0.2794)
			(end 0.12065 -0.2794)
			(stroke
				(width 0.1)
				(type default)
			)
			(layer "F.Fab")
		)
		(fp_line
			(start 0.120396 0.2794)
			(end -0.12065 0.2794)
			(stroke
				(width 0.1)
				(type default)
			)
			(layer "F.Fab")
		)
		(fp_line
			(start -0.12065 0.2794)
			(end -0.12065 0.3048)
			(stroke
				(width 0.1)
				(type default)
			)
			(layer "F.Fab")
		)
		(fp_line
			(start 0.67945 0.3048)
			(end 0.120396 0.3048)
			(stroke
				(width 0.1)
				(type default)
			)
			(layer "F.Fab")
		)
		(fp_line
			(start 0.120396 0.3048)
			(end 0.120396 0.2794)
			(stroke
				(width 0.1)
				(type default)
			)
			(layer "F.Fab")
		)
		(fp_line
			(start -0.12065 0.3048)
			(end -0.67945 0.3048)
			(stroke
				(width 0.1)
				(type default)
			)
			(layer "F.Fab")
		)
		(fp_line
			(start -0.67945 0.3048)
			(end -0.67945 -0.305054)
			(stroke
				(width 0.1)
				(type default)
			)
			(layer "F.Fab")
		)
		(pad "1" smd circle
			(at -0.40005 0 90)
			(size 0 0)
			(layers "F.Cu" "F.Mask" "F.Paste")
			(net "SW_P1V8_PCH_AUX_FLT")
		)
		(pad "2" smd circle
			(at 0.40005 0 90)
			(size 0 0)
			(layers "F.Cu" "F.Mask" "F.Paste")
			(net "GND")
		)
	)
)
